#ISCELL
  pure_quanta quanta_title_block_c *
  *
#ISCELL
  standard offpage *
  page167_i107
#ISCELL
  standard offpage *
  page167_i108
#ISCELL
  standard tap *
  page167_i109
#ISCELL
  standard tap *
  page167_i110
#ISCELL
  standard tap *
  page167_i111
#ISCELL
  standard tap *
  page167_i112
#ISCELL
  standard tap *
  page167_i113
#ISCELL
  standard tap *
  page167_i114
#ISCELL
  standard tap *
  page167_i115
#ISCELL
  standard tap *
  page167_i116
#ISCELL
  standard tap *
  page167_i117
#ISCELL
  standard tap *
  page167_i118
#ISCELL
  standard tap *
  page167_i119
#ISCELL
  standard tap *
  page167_i120
#ISCELL
  standard tap *
  page167_i121
#CELL
  pure_quanta q_cap_diffbus *
  page167_i122
#CELL
  pure_quanta q_cap_diffbus *
  page167_i123
#CELL
  pure_quanta q_cap_diffbus *
  page167_i124
#CELL
  pure_quanta q_cap_diffbus *
  page167_i125
#CELL
  pure_quanta q_cap_diffbus *
  page167_i126
#CELL
  pure_quanta q_cap_diffbus *
  page167_i127
#CELL
  pure_quanta q_cap_diffbus *
  page167_i128
#CELL
  pure_quanta q_cap_diffbus *
  page167_i129
#CELL
  pure_quanta q_cap_diffbus *
  page167_i130
#CELL
  pure_quanta q_cap_diffbus *
  page167_i131
#ISCELL
  standard tap *
  page167_i132
#ISCELL
  standard tap *
  page167_i133
#ISCELL
  standard tap *
  page167_i134
#CELL
  pure_quanta q_cap_diffbus *
  page167_i135
#CELL
  pure_quanta q_cap_diffbus *
  page167_i136
#CELL
  pure_quanta q_cap_diffbus *
  page167_i137
#CELL
  pure_quanta q_cap_diffbus *
  page167_i138
#CELL
  pure_quanta q_cap_diffbus *
  page167_i139
#CELL
  pure_quanta q_cap_diffbus *
  page167_i140
#ISCELL
  standard tap *
  page167_i141
#ISCELL
  standard tap *
  page167_i142
#ISCELL
  standard tap *
  page167_i143
#ISCELL
  standard tap *
  page167_i144
#ISCELL
  standard tap *
  page167_i145
#ISCELL
  standard tap *
  page167_i146
#ISCELL
  standard tap *
  page167_i147
#ISCELL
  standard tap *
  page167_i148
#ISCELL
  standard tap *
  page167_i149
#ISCELL
  standard tap *
  page167_i150
#ISCELL
  standard tap *
  page167_i151
#ISCELL
  standard tap *
  page167_i152
#ISCELL
  standard tap *
  page167_i153
#CELL
  pure_quanta q_cap_diffbus *
  page167_i154
#CELL
  pure_quanta q_cap_diffbus *
  page167_i155
#CELL
  pure_quanta q_cap_diffbus *
  page167_i156
#CELL
  pure_quanta q_cap_diffbus *
  page167_i157
#CELL
  pure_quanta q_cap_diffbus *
  page167_i158
#CELL
  pure_quanta q_cap_diffbus *
  page167_i159
#CELL
  pure_quanta q_cap_diffbus *
  page167_i160
#CELL
  pure_quanta q_cap_diffbus *
  page167_i161
#CELL
  pure_quanta q_cap_diffbus *
  page167_i162
#CELL
  pure_quanta q_cap_diffbus *
  page167_i163
#ISCELL
  standard tap *
  page167_i164
#ISCELL
  standard tap *
  page167_i165
#ISCELL
  standard tap *
  page167_i166
#CELL
  pure_quanta q_cap_diffbus *
  page167_i167
#CELL
  pure_quanta q_cap_diffbus *
  page167_i168
#CELL
  pure_quanta q_cap_diffbus *
  page167_i169
#CELL
  pure_quanta q_cap_diffbus *
  page167_i170
#CELL
  pure_quanta q_cap_diffbus *
  page167_i171
#CELL
  pure_quanta q_cap_diffbus *
  page167_i172
#ISCELL
  standard tap *
  page167_i173
#ISCELL
  standard tap *
  page167_i174
#ISCELL
  standard tap *
  page167_i175
#ISCELL
  standard tap *
  page167_i176
#ISCELL
  standard tap *
  page167_i177
#ISCELL
  standard tap *
  page167_i178
#ISCELL
  standard tap *
  page167_i179
#ISCELL
  standard tap *
  page167_i180
#ISCELL
  standard tap *
  page167_i181
#ISCELL
  standard tap *
  page167_i182
#ISCELL
  standard tap *
  page167_i183
#ISCELL
  standard tap *
  page167_i184
#ISCELL
  standard tap *
  page167_i185
#ISCELL
  standard tap *
  page167_i186
#ISCELL
  standard tap *
  page167_i187
#ISCELL
  standard tap *
  page167_i188
#ISCELL
  standard offpage *
  page167_i189
#ISCELL
  standard offpage *
  page167_i190
#ISCELL
  standard tap *
  page167_i191
#ISCELL
  standard tap *
  page167_i192
#ISCELL
  standard tap *
  page167_i193
#ISCELL
  standard tap *
  page167_i194
#ISCELL
  standard tap *
  page167_i195
#ISCELL
  standard tap *
  page167_i196
#ISCELL
  standard tap *
  page167_i197
#ISCELL
  standard tap *
  page167_i198
#ISCELL
  standard tap *
  page167_i199
#ISCELL
  standard tap *
  page167_i200
#ISCELL
  standard tap *
  page167_i201
#ISCELL
  standard tap *
  page167_i202
#ISCELL
  standard tap *
  page167_i203
#ISCELL
  standard tap *
  page167_i204
#ISCELL
  standard tap *
  page167_i205
#ISCELL
  standard tap *
  page167_i206
#ISCELL
  standard offpage *
  page167_i207
#ISCELL
  standard offpage *
  page167_i208
#ISCELL
  standard offpage *
  page167_i209
#ISCELL
  standard offpage *
  page167_i210
#ISCELL
  standard offpage *
  page167_i211
#ISCELL
  standard offpage *
  page167_i212
#ISCELL
  standard tap *
  page167_i213
#ISCELL
  standard tap *
  page167_i214
#ISCELL
  standard tap *
  page167_i215
#ISCELL
  standard tap *
  page167_i216
#ISCELL
  standard tap *
  page167_i217
#ISCELL
  standard tap *
  page167_i218
#ISCELL
  standard tap *
  page167_i219
#ISCELL
  standard tap *
  page167_i220
#ISCELL
  standard tap *
  page167_i221
#ISCELL
  standard tap *
  page167_i222
#ISCELL
  standard tap *
  page167_i223
#ISCELL
  standard tap *
  page167_i224
#ISCELL
  standard tap *
  page167_i225
#ISCELL
  standard tap *
  page167_i226
#ISCELL
  standard tap *
  page167_i227
#ISCELL
  standard tap *
  page167_i228
#CELL
  pure_quanta q_cap_diffbus *
  page167_i229
#CELL
  pure_quanta q_cap_diffbus *
  page167_i230
#CELL
  pure_quanta q_cap_diffbus *
  page167_i231
#CELL
  pure_quanta q_cap_diffbus *
  page167_i232
#CELL
  pure_quanta q_cap_diffbus *
  page167_i233
#CELL
  pure_quanta q_cap_diffbus *
  page167_i234
#CELL
  pure_quanta q_cap_diffbus *
  page167_i235
#CELL
  pure_quanta q_cap_diffbus *
  page167_i236
#CELL
  pure_quanta q_cap_diffbus *
  page167_i237
#ISCELL
  standard tap *
  page167_i238
#ISCELL
  standard tap *
  page167_i239
#ISCELL
  standard tap *
  page167_i240
#ISCELL
  standard tap *
  page167_i241
#ISCELL
  standard tap *
  page167_i242
#ISCELL
  standard tap *
  page167_i243
#ISCELL
  standard tap *
  page167_i244
#ISCELL
  standard tap *
  page167_i245
#CELL
  pure_quanta q_cap_diffbus *
  page167_i246
#CELL
  pure_quanta q_cap_diffbus *
  page167_i247
#CELL
  pure_quanta q_cap_diffbus *
  page167_i248
#CELL
  pure_quanta q_cap_diffbus *
  page167_i249
#CELL
  pure_quanta q_cap_diffbus *
  page167_i250
#CELL
  pure_quanta q_cap_diffbus *
  page167_i251
#ISCELL
  standard tap *
  page167_i252
#ISCELL
  standard tap *
  page167_i253
#ISCELL
  standard tap *
  page167_i254
#ISCELL
  standard tap *
  page167_i255
#ISCELL
  standard tap *
  page167_i256
#ISCELL
  standard tap *
  page167_i257
#ISCELL
  standard tap *
  page167_i258
#ISCELL
  standard tap *
  page167_i259
#ISCELL
  standard tap *
  page167_i260
#ISCELL
  standard tap *
  page167_i261
#ISCELL
  standard tap *
  page167_i262
#ISCELL
  standard tap *
  page167_i263
#ISCELL
  standard tap *
  page167_i264
#ISCELL
  standard tap *
  page167_i265
#ISCELL
  standard tap *
  page167_i266
#ISCELL
  standard tap *
  page167_i267
#ISCELL
  standard tap *
  page167_i268
#ISCELL
  standard tap *
  page167_i269
#ISCELL
  standard tap *
  page167_i270
#ISCELL
  standard tap *
  page167_i271
#ISCELL
  standard tap *
  page167_i272
#ISCELL
  standard tap *
  page167_i273
#CELL
  pure_quanta q_cap_diffbus *
  page167_i274
#CELL
  pure_quanta q_cap_diffbus *
  page167_i275
#CELL
  pure_quanta q_cap_diffbus *
  page167_i276
#CELL
  pure_quanta q_cap_diffbus *
  page167_i277
#CELL
  pure_quanta q_cap_diffbus *
  page167_i278
#CELL
  pure_quanta q_cap_diffbus *
  page167_i279
#CELL
  pure_quanta q_cap_diffbus *
  page167_i280
#CELL
  pure_quanta q_cap_diffbus *
  page167_i281
#CELL
  pure_quanta q_cap_diffbus *
  page167_i282
#CELL
  pure_quanta q_cap_diffbus *
  page167_i283
#ISCELL
  standard tap *
  page167_i284
#ISCELL
  standard tap *
  page167_i285
#ISCELL
  standard tap *
  page167_i286
#ISCELL
  standard tap *
  page167_i287
#ISCELL
  standard tap *
  page167_i288
#ISCELL
  standard tap *
  page167_i289
#ISCELL
  standard tap *
  page167_i290
#ISCELL
  standard tap *
  page167_i291
#ISCELL
  standard tap *
  page167_i292
#ISCELL
  standard tap *
  page167_i293
#CELL
  pure_quanta q_cap_diffbus *
  page167_i294
#CELL
  pure_quanta q_cap_diffbus *
  page167_i295
#CELL
  pure_quanta q_cap_diffbus *
  page167_i296
#CELL
  pure_quanta q_cap_diffbus *
  page167_i297
#CELL
  pure_quanta q_cap_diffbus *
  page167_i298
#CELL
  pure_quanta q_cap_diffbus *
  page167_i299
#ISCELL
  standard tap *
  page167_i300
#ISCELL
  standard tap *
  page167_i301
#ISCELL
  standard tap *
  page167_i302
#ISCELL
  standard tap *
  page167_i303
#ISCELL
  standard tap *
  page167_i304
#ISCELL
  standard tap *
  page167_i305
#ISCELL
  standard offpage *
  page167_i306
#ISCELL
  standard offpage *
  page167_i307
#ISCELL
  standard offpage *
  page167_i308
#ISCELL
  standard offpage *
  page167_i309
#ISCELL
  standard tap *
  page167_i310
#ISCELL
  standard tap *
  page167_i311
#CELL
  pure_quanta q_cap_diffbus *
  page167_i312
#ISCELL
  standard offpage *
  page167_i95
#ISCELL
  standard offpage *
  page167_i96
